(kicad_pcb
	(version 20260206)
	(generator "pcbnew")
	(generator_version "10.0")
	(general
		(thickness 1.6)
		(legacy_teardrops no)
	)
	(paper "A4")
	(title_block
		(title "peb — Lightning_PEB_BRD.brd")
		(comment 1 "Lightning (Wiwynn / Facebook NVMe JBOF) / footprints 2138-2145 of 2563")
	)
	(layers
		(0 "F.Cu" signal "TOP")
		(4 "In1.Cu" signal "L2GND")
		(6 "In2.Cu" signal "L3")
		(8 "In3.Cu" signal "L4VCC")
		(10 "In4.Cu" signal "L5VCC")
		(12 "In5.Cu" signal "L6")
		(14 "In6.Cu" signal "L7GND")
		(2 "B.Cu" signal "BOTTOM")
		(9 "F.Adhes" user "F.Adhesive")
		(11 "B.Adhes" user "B.Adhesive")
		(13 "F.Paste" user "Package Geometry/Pastemask Top")
		(15 "B.Paste" user "Package Geometry/Pastemask Bottom")
		(5 "F.SilkS" user "Ref Des/Silkscreen Top")
		(7 "B.SilkS" user "Ref Des/Silkscreen Bottom")
		(1 "F.Mask" user "Board Geometry/Soldermask Top")
		(3 "B.Mask" user "Board Geometry/Soldermask Bottom")
		(17 "Dwgs.User" user "User.Drawings")
		(19 "Cmts.User" user "User.Comments")
		(21 "Eco1.User" user "User.Eco1")
		(23 "Eco2.User" user "User.Eco2")
		(25 "Edge.Cuts" user "Board Geometry/Outline")
		(27 "Margin" user)
		(31 "F.CrtYd" user "Package Geometry/Place Bound Top")
		(29 "B.CrtYd" user "Package Geometry/Place Bound Bottom")
		(35 "F.Fab" user "Ref Des/Assembly Top")
		(33 "B.Fab" user "Ref Des/Assembly Bottom")
	)
	(footprint ""
		(layer "B.Cu")
		(at 148.428202 -56.542432)
		(property "Reference" "PR173"
			(at 0 0 0)
			(layer "B.SilkS")
			(hide yes)
			(effects
				(font
					(size 1.27 1.27)
				)
				(justify mirror)
			)
		)
		(property "Value" "100KR2F-L1-GP"
			(at -0.064008 -3.993896 0)
			(unlocked yes)
			(layer "B.Fab")
			(hide yes)
			(effects
				(font
					(size 1.016 1.016)
					(thickness 0.1524)
				)
				(justify mirror)
			)
		)
		(property "Device Type" "R402H16"
			(at -0.064008 -5.517896 0)
			(unlocked yes)
			(layer "B.Fab")
			(hide yes)
			(effects
				(font
					(size 1.016 1.016)
					(thickness 0.1524)
				)
				(justify mirror)
			)
		)
		(duplicate_pad_numbers_are_jumpers no)
		(fp_line
			(start -0.508 -0.9398)
			(end 0.508 -0.9398)
			(stroke
				(width 0.1524)
				(type default)
			)
			(layer "B.SilkS")
		)
		(fp_line
			(start 0.508 -0.9398)
			(end 0.508 0.9398)
			(stroke
				(width 0.1524)
				(type default)
			)
			(layer "B.SilkS")
		)
		(fp_rect
			(start 0.508 0.9398)
			(end -0.508 -0.9398)
			(stroke
				(width 0)
				(type default)
			)
			(fill no)
			(layer "B.CrtYd")
		)
		(fp_rect
			(start 0.508 0.9398)
			(end -0.508 -0.9398)
			(stroke
				(width 0)
				(type default)
			)
			(fill no)
			(layer "B.Fab")
		)
		(pad "1" smd custom
			(at 0 -0.4445 180)
			(size 0.1397 0.1397)
			(layers "B.Cu" "B.Mask" "B.Paste")
			(net "P0V9_MODE")
			(options
				(clearance outline)
				(anchor circle)
			)
			(primitives
				(gr_poly
					(pts
						(arc
							(start -0.1778 0.2794)
							(mid -0.249642 0.249642)
							(end -0.2794 0.1778)
						)
						(arc
							(start -0.2794 -0.1778)
							(mid -0.249642 -0.249642)
							(end -0.1778 -0.2794)
						)
						(arc
							(start 0.1778 -0.2794)
							(mid 0.249642 -0.249642)
							(end 0.2794 -0.1778)
						)
						(arc
							(start 0.2794 0.1778)
							(mid 0.249642 0.249642)
							(end 0.1778 0.2794)
						)
					)
					(width 0)
					(fill yes)
				)
			)
		)
		(pad "2" smd custom
			(at 0 0.4445 180)
			(size 0.1397 0.1397)
			(layers "B.Cu" "B.Mask" "B.Paste")
			(net "AGND_P0V9")
			(options
				(clearance outline)
				(anchor circle)
			)
			(primitives
				(gr_poly
					(pts
						(arc
							(start -0.1778 0.2794)
							(mid -0.249642 0.249642)
							(end -0.2794 0.1778)
						)
						(arc
							(start -0.2794 -0.1778)
							(mid -0.249642 -0.249642)
							(end -0.1778 -0.2794)
						)
						(arc
							(start 0.1778 -0.2794)
							(mid 0.249642 -0.249642)
							(end 0.2794 -0.1778)
						)
						(arc
							(start 0.2794 0.1778)
							(mid 0.249642 0.249642)
							(end 0.1778 0.2794)
						)
					)
					(width 0)
					(fill yes)
				)
			)
		)
	)
	(footprint ""
		(layer "B.Cu")
		(at 235.1024 -48.9966 90)
		(property "Reference" "C36"
			(at 0 0 90)
			(layer "B.SilkS")
			(hide yes)
			(effects
				(font
					(size 1.27 1.27)
				)
				(justify mirror)
			)
		)
		(property "Value" "SCD1U16V1KX-1-GP"
			(at 2.8321 -1.7399 90)
			(unlocked yes)
			(layer "B.Fab")
			(hide yes)
			(effects
				(font
					(size 1.016 1.016)
					(thickness 0.1524)
				)
				(justify mirror)
			)
		)
		(property "Device Type" "C0201H13"
			(at 2.8321 -3.2639 90)
			(unlocked yes)
			(layer "B.Fab")
			(hide yes)
			(effects
				(font
					(size 1.016 1.016)
					(thickness 0.1524)
				)
				(justify mirror)
			)
		)
		(duplicate_pad_numbers_are_jumpers no)
		(fp_rect
			(start 0.2794 0.6477)
			(end -0.2794 -0.6477)
			(stroke
				(width 0)
				(type default)
			)
			(fill no)
			(layer "B.CrtYd")
		)
		(fp_rect
			(start 0.2794 0.6477)
			(end -0.2794 -0.6477)
			(stroke
				(width 0)
				(type default)
			)
			(fill no)
			(layer "B.Fab")
		)
		(pad "1" smd custom
			(at 0 -0.2794 270)
			(size 0.0762 0.0762)
			(layers "B.Cu" "B.Mask" "B.Paste")
			(net "DUT_VDD")
			(options
				(clearance outline)
				(anchor circle)
			)
			(primitives
				(gr_poly
					(pts
						(arc
							(start 0.1524 0.127)
							(mid 0.137521 0.162921)
							(end 0.1016 0.1778)
						)
						(arc
							(start -0.1016 0.1778)
							(mid -0.137521 0.162921)
							(end -0.1524 0.127)
						)
						(arc
							(start -0.1524 -0.127)
							(mid -0.137521 -0.162921)
							(end -0.1016 -0.1778)
						)
						(arc
							(start 0.1016 -0.1778)
							(mid 0.137521 -0.162921)
							(end 0.1524 -0.127)
						)
					)
					(width 0)
					(fill yes)
				)
			)
		)
		(pad "2" smd custom
			(at 0 0.2794 270)
			(size 0.0762 0.0762)
			(layers "B.Cu" "B.Mask" "B.Paste")
			(net "GND")
			(options
				(clearance outline)
				(anchor circle)
			)
			(primitives
				(gr_poly
					(pts
						(arc
							(start 0.1524 0.127)
							(mid 0.137521 0.162921)
							(end 0.1016 0.1778)
						)
						(arc
							(start -0.1016 0.1778)
							(mid -0.137521 0.162921)
							(end -0.1524 0.127)
						)
						(arc
							(start -0.1524 -0.127)
							(mid -0.137521 -0.162921)
							(end -0.1016 -0.1778)
						)
						(arc
							(start 0.1016 -0.1778)
							(mid 0.137521 -0.162921)
							(end 0.1524 -0.127)
						)
					)
					(width 0)
					(fill yes)
				)
			)
		)
	)
	(footprint ""
		(layer "B.Cu")
		(at 53.7845 -125.918976 -90)
		(property "Reference" "R335"
			(at 0 0 90)
			(layer "B.SilkS")
			(hide yes)
			(effects
				(font
					(size 1.27 1.27)
				)
				(justify mirror)
			)
		)
		(property "Value" "10KR2F-2-GP"
			(at -0.064008 -3.993896 270)
			(unlocked yes)
			(layer "B.Fab")
			(hide yes)
			(effects
				(font
					(size 1.016 1.016)
					(thickness 0.1524)
				)
				(justify mirror)
			)
		)
		(property "Device Type" "R402H16"
			(at -0.064008 -5.517896 270)
			(unlocked yes)
			(layer "B.Fab")
			(hide yes)
			(effects
				(font
					(size 1.016 1.016)
					(thickness 0.1524)
				)
				(justify mirror)
			)
		)
		(duplicate_pad_numbers_are_jumpers no)
		(fp_line
			(start -0.508 -0.9398)
			(end 0.508 -0.9398)
			(stroke
				(width 0.1524)
				(type default)
			)
			(layer "B.SilkS")
		)
		(fp_line
			(start 0.508 -0.9398)
			(end 0.508 0.9398)
			(stroke
				(width 0.1524)
				(type default)
			)
			(layer "B.SilkS")
		)
		(fp_rect
			(start 0.508 0.9398)
			(end -0.508 -0.9398)
			(stroke
				(width 0)
				(type default)
			)
			(fill no)
			(layer "B.CrtYd")
		)
		(fp_rect
			(start 0.508 0.9398)
			(end -0.508 -0.9398)
			(stroke
				(width 0)
				(type default)
			)
			(fill no)
			(layer "B.Fab")
		)
		(pad "1" smd custom
			(at 0 -0.4445 90)
			(size 0.1397 0.1397)
			(layers "B.Cu" "B.Mask" "B.Paste")
			(net "GND")
			(options
				(clearance outline)
				(anchor circle)
			)
			(primitives
				(gr_poly
					(pts
						(arc
							(start -0.1778 0.2794)
							(mid -0.249642 0.249642)
							(end -0.2794 0.1778)
						)
						(arc
							(start -0.2794 -0.1778)
							(mid -0.249642 -0.249642)
							(end -0.1778 -0.2794)
						)
						(arc
							(start 0.1778 -0.2794)
							(mid 0.249642 -0.249642)
							(end 0.2794 -0.1778)
						)
						(arc
							(start 0.2794 0.1778)
							(mid 0.249642 0.249642)
							(end 0.1778 0.2794)
						)
					)
					(width 0)
					(fill yes)
				)
			)
		)
		(pad "2" smd custom
			(at 0 0.4445 90)
			(size 0.1397 0.1397)
			(layers "B.Cu" "B.Mask" "B.Paste")
			(net "BMC0_JTAG_RTCK")
			(options
				(clearance outline)
				(anchor circle)
			)
			(primitives
				(gr_poly
					(pts
						(arc
							(start -0.1778 0.2794)
							(mid -0.249642 0.249642)
							(end -0.2794 0.1778)
						)
						(arc
							(start -0.2794 -0.1778)
							(mid -0.249642 -0.249642)
							(end -0.1778 -0.2794)
						)
						(arc
							(start 0.1778 -0.2794)
							(mid 0.249642 -0.249642)
							(end 0.2794 -0.1778)
						)
						(arc
							(start 0.2794 0.1778)
							(mid 0.249642 0.249642)
							(end 0.1778 0.2794)
						)
					)
					(width 0)
					(fill yes)
				)
			)
		)
	)
	(footprint ""
		(layer "B.Cu")
		(at 237.617 -59.0042 90)
		(property "Reference" "C529"
			(at 0 0 90)
			(layer "B.SilkS")
			(hide yes)
			(effects
				(font
					(size 1.27 1.27)
				)
				(justify mirror)
			)
		)
		(property "Value" "SCD1U16V1KX-1-GP"
			(at 2.8321 -1.7399 90)
			(unlocked yes)
			(layer "B.Fab")
			(hide yes)
			(effects
				(font
					(size 1.016 1.016)
					(thickness 0.1524)
				)
				(justify mirror)
			)
		)
		(property "Device Type" "C0201H13"
			(at 2.8321 -3.2639 90)
			(unlocked yes)
			(layer "B.Fab")
			(hide yes)
			(effects
				(font
					(size 1.016 1.016)
					(thickness 0.1524)
				)
				(justify mirror)
			)
		)
		(duplicate_pad_numbers_are_jumpers no)
		(fp_rect
			(start 0.2794 0.6477)
			(end -0.2794 -0.6477)
			(stroke
				(width 0)
				(type default)
			)
			(fill no)
			(layer "B.CrtYd")
		)
		(fp_rect
			(start 0.2794 0.6477)
			(end -0.2794 -0.6477)
			(stroke
				(width 0)
				(type default)
			)
			(fill no)
			(layer "B.Fab")
		)
		(pad "1" smd custom
			(at 0 -0.2794 270)
			(size 0.0762 0.0762)
			(layers "B.Cu" "B.Mask" "B.Paste")
			(net "DUT_AVD_TX")
			(options
				(clearance outline)
				(anchor circle)
			)
			(primitives
				(gr_poly
					(pts
						(arc
							(start 0.1524 0.127)
							(mid 0.137521 0.162921)
							(end 0.1016 0.1778)
						)
						(arc
							(start -0.1016 0.1778)
							(mid -0.137521 0.162921)
							(end -0.1524 0.127)
						)
						(arc
							(start -0.1524 -0.127)
							(mid -0.137521 -0.162921)
							(end -0.1016 -0.1778)
						)
						(arc
							(start 0.1016 -0.1778)
							(mid 0.137521 -0.162921)
							(end 0.1524 -0.127)
						)
					)
					(width 0)
					(fill yes)
				)
			)
		)
		(pad "2" smd custom
			(at 0 0.2794 270)
			(size 0.0762 0.0762)
			(layers "B.Cu" "B.Mask" "B.Paste")
			(net "GND")
			(options
				(clearance outline)
				(anchor circle)
			)
			(primitives
				(gr_poly
					(pts
						(arc
							(start 0.1524 0.127)
							(mid 0.137521 0.162921)
							(end 0.1016 0.1778)
						)
						(arc
							(start -0.1016 0.1778)
							(mid -0.137521 0.162921)
							(end -0.1524 0.127)
						)
						(arc
							(start -0.1524 -0.127)
							(mid -0.137521 -0.162921)
							(end -0.1016 -0.1778)
						)
						(arc
							(start 0.1016 -0.1778)
							(mid 0.137521 -0.162921)
							(end 0.1524 -0.127)
						)
					)
					(width 0)
					(fill yes)
				)
			)
		)
	)
	(footprint ""
		(layer "B.Cu")
		(at 175.961802 -71.071232 90)
		(property "Reference" "PG34"
			(at 0 0 90)
			(layer "B.SilkS")
			(hide yes)
			(effects
				(font
					(size 1.27 1.27)
				)
				(justify mirror)
			)
		)
		(property "Value" "GAP-CLOSE-PWR-3-GP"
			(at -0.0254 -6.5786 90)
			(unlocked yes)
			(layer "B.Fab")
			(hide yes)
			(effects
				(font
					(size 1.016 1.016)
					(thickness 0.1524)
				)
				(justify mirror)
			)
		)
		(property "Device Type" "GAP-CLOSE-PWR-3"
			(at -0.0254 -8.255 90)
			(unlocked yes)
			(layer "B.Fab")
			(hide yes)
			(effects
				(font
					(size 1.016 1.016)
					(thickness 0.1524)
				)
				(justify mirror)
			)
		)
		(duplicate_pad_numbers_are_jumpers no)
		(fp_rect
			(start 0.7112 0.4572)
			(end -0.7112 -0.4572)
			(stroke
				(width 0)
				(type default)
			)
			(fill no)
			(layer "B.CrtYd")
		)
		(fp_poly
			(pts
				(xy 0.7112 -0.4572) (xy -0.7112 -0.4572) (xy -0.7112 0.4572) (xy 0.7112 0.4572)
			)
			(stroke
				(width 0)
				(type default)
			)
			(fill no)
			(layer "B.Fab")
		)
		(pad "1" smd rect
			(at 0.3048 0 270)
			(size 0.6604 0.762)
			(layers "B.Cu" "B.Mask" "B.Paste")
			(net "DUT_AVD_TX")
		)
		(pad "2" smd rect
			(at -0.3048 0 270)
			(size 0.6604 0.762)
			(layers "B.Cu" "B.Mask" "B.Paste")
			(net "P0V9")
		)
	)
	(footprint ""
		(layer "B.Cu")
		(at 315.140086 -37.732462 180)
		(property "Reference" "C231"
			(at 0 0 0)
			(layer "B.SilkS")
			(hide yes)
			(effects
				(font
					(size 1.27 1.27)
				)
				(justify mirror)
			)
		)
		(property "Value" "SCD1U10V2KX-5GP"
			(at -1.1811 -2.7051 180)
			(unlocked yes)
			(layer "B.Fab")
			(hide yes)
			(effects
				(font
					(size 1.016 1.016)
					(thickness 0.1524)
				)
				(justify mirror)
			)
		)
		(property "Device Type" "C402H22"
			(at -1.1811 -4.2291 180)
			(unlocked yes)
			(layer "B.Fab")
			(hide yes)
			(effects
				(font
					(size 1.016 1.016)
					(thickness 0.1524)
				)
				(justify mirror)
			)
		)
		(duplicate_pad_numbers_are_jumpers no)
		(fp_rect
			(start 0.4318 0.9525)
			(end -0.4318 -0.9525)
			(stroke
				(width 0)
				(type default)
			)
			(fill no)
			(layer "B.CrtYd")
		)
		(fp_rect
			(start 0.4318 0.9525)
			(end -0.4318 -0.9525)
			(stroke
				(width 0)
				(type default)
			)
			(fill no)
			(layer "B.Fab")
		)
		(pad "1" smd custom
			(at 0 -0.4445)
			(size 0.1524 0.1524)
			(layers "B.Cu" "B.Mask" "B.Paste")
			(net "GND")
			(options
				(clearance outline)
				(anchor circle)
			)
			(primitives
				(gr_poly
					(pts
						(arc
							(start 0.3048 0.2032)
							(mid 0.275042 0.275042)
							(end 0.2032 0.3048)
						)
						(arc
							(start -0.2032 0.3048)
							(mid -0.275042 0.275042)
							(end -0.3048 0.2032)
						)
						(arc
							(start -0.3048 -0.2032)
							(mid -0.275042 -0.275042)
							(end -0.2032 -0.3048)
						)
						(arc
							(start 0.2032 -0.3048)
							(mid 0.275042 -0.275042)
							(end 0.3048 -0.2032)
						)
					)
					(width 0)
					(fill yes)
				)
			)
		)
		(pad "2" smd custom
			(at 0 0.4445)
			(size 0.1524 0.1524)
			(layers "B.Cu" "B.Mask" "B.Paste")
			(net "P3V3_STBY")
			(options
				(clearance outline)
				(anchor circle)
			)
			(primitives
				(gr_poly
					(pts
						(arc
							(start 0.3048 0.2032)
							(mid 0.275042 0.275042)
							(end 0.2032 0.3048)
						)
						(arc
							(start -0.2032 0.3048)
							(mid -0.275042 0.275042)
							(end -0.3048 0.2032)
						)
						(arc
							(start -0.3048 -0.2032)
							(mid -0.275042 -0.275042)
							(end -0.2032 -0.3048)
						)
						(arc
							(start 0.2032 -0.3048)
							(mid 0.275042 -0.275042)
							(end 0.3048 -0.2032)
						)
					)
					(width 0)
					(fill yes)
				)
			)
		)
	)
	(footprint ""
		(layer "B.Cu")
		(at 147.920202 -59.336432)
		(property "Reference" "PC212"
			(at 0 0 0)
			(layer "B.SilkS")
			(hide yes)
			(effects
				(font
					(size 1.27 1.27)
				)
				(justify mirror)
			)
		)
		(property "Value" "SC4D7U25V5KX-1-GP"
			(at 0.0762 -6.1214 0)
			(unlocked yes)
			(layer "B.Fab")
			(hide yes)
			(effects
				(font
					(size 1.016 1.016)
					(thickness 0.1524)
				)
				(justify mirror)
			)
		)
		(property "Device Type" "C805H58"
			(at 0.0762 -8.1534 0)
			(unlocked yes)
			(layer "B.Fab")
			(hide yes)
			(effects
				(font
					(size 1.016 1.016)
					(thickness 0.1524)
				)
				(justify mirror)
			)
		)
		(duplicate_pad_numbers_are_jumpers no)
		(fp_line
			(start -0.635 0)
			(end 0.635 0)
			(stroke
				(width 0.508)
				(type default)
			)
			(layer "B.SilkS")
		)
		(fp_rect
			(start 0.9652 1.778)
			(end -0.9652 -1.778)
			(stroke
				(width 0)
				(type default)
			)
			(fill no)
			(layer "B.CrtYd")
		)
		(fp_poly
			(pts
				(xy 0.9652 -1.778) (xy -0.9652 -1.778) (xy -0.9652 1.778) (xy 0.9652 1.778)
			)
			(stroke
				(width 0)
				(type default)
			)
			(fill no)
			(layer "B.Fab")
		)
		(pad "1" smd rect
			(at 0 -0.9652 180)
			(size 1.397 1.143)
			(layers "B.Cu" "B.Mask" "B.Paste")
			(net "P0V9_VDD")
		)
		(pad "2" smd rect
			(at 0 0.9652 180)
			(size 1.397 1.143)
			(layers "B.Cu" "B.Mask" "B.Paste")
			(net "GND")
		)
	)
	(footprint ""
		(layer "B.Cu")
		(at 273.2786 -3.1496 90)
		(property "Reference" "R2914"
			(at 0 0 90)
			(layer "B.SilkS")
			(hide yes)
			(effects
				(font
					(size 1.27 1.27)
				)
				(justify mirror)
			)
		)
		(property "Value" "0R2J-2-GP"
			(at -0.064008 -3.993896 90)
			(unlocked yes)
			(layer "B.Fab")
			(hide yes)
			(effects
				(font
					(size 1.016 1.016)
					(thickness 0.1524)
				)
				(justify mirror)
			)
		)
		(property "Device Type" "R402H16"
			(at -0.064008 -5.517896 90)
			(unlocked yes)
			(layer "B.Fab")
			(hide yes)
			(effects
				(font
					(size 1.016 1.016)
					(thickness 0.1524)
				)
				(justify mirror)
			)
		)
		(duplicate_pad_numbers_are_jumpers no)
		(fp_line
			(start 0.508 -0.9398)
			(end 0.508 0.9398)
			(stroke
				(width 0.1524)
				(type default)
			)
			(layer "B.SilkS")
		)
		(fp_line
			(start -0.508 -0.9398)
			(end 0.508 -0.9398)
			(stroke
				(width 0.1524)
				(type default)
			)
			(layer "B.SilkS")
		)
		(fp_rect
			(start 0.508 0.9398)
			(end -0.508 -0.9398)
			(stroke
				(width 0)
				(type default)
			)
			(fill no)
			(layer "B.CrtYd")
		)
		(fp_rect
			(start 0.508 0.9398)
			(end -0.508 -0.9398)
			(stroke
				(width 0)
				(type default)
			)
			(fill no)
			(layer "B.Fab")
		)
		(pad "1" smd custom
			(at 0 -0.4445 270)
			(size 0.1397 0.1397)
			(layers "B.Cu" "B.Mask" "B.Paste")
			(net "BMC_I2C14_MINI8_SDA")
			(options
				(clearance outline)
				(anchor circle)
			)
			(primitives
				(gr_poly
					(pts
						(arc
							(start -0.1778 0.2794)
							(mid -0.249642 0.249642)
							(end -0.2794 0.1778)
						)
						(arc
							(start -0.2794 -0.1778)
							(mid -0.249642 -0.249642)
							(end -0.1778 -0.2794)
						)
						(arc
							(start 0.1778 -0.2794)
							(mid 0.249642 -0.249642)
							(end 0.2794 -0.1778)
						)
						(arc
							(start 0.2794 0.1778)
							(mid 0.249642 0.249642)
							(end 0.1778 0.2794)
						)
					)
					(width 0)
					(fill yes)
				)
			)
		)
		(pad "2" smd custom
			(at 0 0.4445 270)
			(size 0.1397 0.1397)
			(layers "B.Cu" "B.Mask" "B.Paste")
			(net "8644_CBL_PRSNT_R_8")
			(options
				(clearance outline)
				(anchor circle)
			)
			(primitives
				(gr_poly
					(pts
						(arc
							(start -0.1778 0.2794)
							(mid -0.249642 0.249642)
							(end -0.2794 0.1778)
						)
						(arc
							(start -0.2794 -0.1778)
							(mid -0.249642 -0.249642)
							(end -0.1778 -0.2794)
						)
						(arc
							(start 0.1778 -0.2794)
							(mid 0.249642 -0.249642)
							(end 0.2794 -0.1778)
						)
						(arc
							(start 0.2794 0.1778)
							(mid 0.249642 0.249642)
							(end 0.1778 0.2794)
						)
					)
					(width 0)
					(fill yes)
				)
			)
		)
	)
)
